(kicad_pcb
	(version 20240108)
	(generator "pcbnew")
	(generator_version "8.0")
	(general
		(thickness 1.62)
		(legacy_teardrops no)
	)
	(paper "A4")
	(title_block
		(title "Jetson Orin Baseboard")
		(date "2025-03-12")
		(rev "1.3.4")
		(company "Antmicro Ltd")
		(comment 1 "www.antmicro.com")
		(comment 9 "footprints 414-417 of 677")
	)
	(layers
		(0 "F.Cu" signal)
		(1 "In1.Cu" signal)
		(2 "In2.Cu" signal)
		(3 "In3.Cu" signal)
		(4 "In4.Cu" jumper)
		(5 "In5.Cu" signal)
		(6 "In6.Cu" signal)
		(31 "B.Cu" signal)
		(32 "B.Adhes" user "B.Adhesive")
		(33 "F.Adhes" user "F.Adhesive")
		(34 "B.Paste" user)
		(35 "F.Paste" user)
		(36 "B.SilkS" user "B.Silkscreen")
		(37 "F.SilkS" user "F.Silkscreen")
		(38 "B.Mask" user)
		(39 "F.Mask" user)
		(40 "Dwgs.User" user "User.Drawings")
		(41 "Cmts.User" user "User.Comments")
		(42 "Eco1.User" user "User.Eco1")
		(43 "Eco2.User" user "User.Eco2")
		(44 "Edge.Cuts" user)
		(45 "Margin" user)
		(46 "B.CrtYd" user "B.Courtyard")
		(47 "F.CrtYd" user "F.Courtyard")
		(48 "B.Fab" user)
		(49 "F.Fab" user)
	)
	(footprint "antmicro-footprints:Spacer_Drill3.7mm_H6.5mm_9774065151R"
		(locked yes)
		(layer "B.Cu")
		(at 39.75 123.75 180)
		(descr "Spacer M=3 h=6.5mm fi=5.1mm")
		(property "Reference" "H4"
			(at 1.63 2.62 0)
			(layer "B.SilkS")
			(effects
				(font
					(size 0.7 0.7)
					(thickness 0.15)
				)
				(justify left bottom mirror)
			)
		)
		(property "Value" "Spacer_Drill3.7mm_H6.5mm_9774065151R"
			(at 0 -4 0)
			(layer "B.Fab")
			(effects
				(font
					(size 0.7 0.7)
					(thickness 0.15)
				)
				(justify left bottom mirror)
			)
		)
		(property "Footprint" "antmicro-footprints:Spacer_Drill3.7mm_H6.5mm_9774065151R"
			(at 0 0 180)
			(layer "F.Fab")
			(hide yes)
			(effects
				(font
					(size 1.27 1.27)
					(thickness 0.15)
				)
			)
		)
		(property "Datasheet" "https://www.we-online.com/components/products/datasheet/9774065151R.pdf"
			(at 0 0 180)
			(layer "F.Fab")
			(hide yes)
			(effects
				(font
					(size 1.27 1.27)
					(thickness 0.15)
				)
			)
		)
		(property "Author" "Antmicro"
			(at 79.5 247.5 0)
			(layer "B.Fab")
			(hide yes)
			(effects
				(font
					(size 1 1)
					(thickness 0.15)
				)
				(justify mirror)
			)
		)
		(property "License" "Apache-2.0"
			(at 79.5 247.5 0)
			(layer "B.Fab")
			(hide yes)
			(effects
				(font
					(size 1 1)
					(thickness 0.15)
				)
				(justify mirror)
			)
		)
		(property "MPN" "9774065151R"
			(at 79.5 247.5 0)
			(layer "B.Fab")
			(hide yes)
			(effects
				(font
					(size 1 1)
					(thickness 0.15)
				)
				(justify mirror)
			)
		)
		(property "Manufacturer" "Würth Elektronik"
			(at 79.5 247.5 0)
			(layer "B.Fab")
			(hide yes)
			(effects
				(font
					(size 1 1)
					(thickness 0.15)
				)
				(justify mirror)
			)
		)
		(sheetname "Root")
		(sheetfile "jetson-orin-baseboard.kicad_sch")
		(solder_paste_ratio -1)
		(attr smd)
		(fp_circle
			(center 0 0)
			(end 3.05 0)
			(stroke
				(width 0.05)
				(type solid)
			)
			(fill none)
			(layer "B.CrtYd")
		)
		(fp_circle
			(center 0 0)
			(end 2.6 0)
			(stroke
				(width 0.15)
				(type solid)
			)
			(fill none)
			(layer "B.Fab")
		)
		(fp_text user "Author: Antmicro"
			(at -9.6 -7.7 0)
			(layer "B.Fab")
			(hide yes)
			(effects
				(font
					(size 0.7 0.7)
					(thickness 0.15)
				)
				(justify left bottom mirror)
			)
		)
		(fp_text user "License: Apache-2.0"
			(at -9.6 -8.9 0)
			(layer "B.Fab")
			(hide yes)
			(effects
				(font
					(size 0.7 0.7)
					(thickness 0.15)
				)
				(justify left bottom mirror)
			)
		)
		(fp_text user "${REFERENCE}"
			(at -9.6 -6.5 0)
			(layer "B.Fab")
			(hide yes)
			(effects
				(font
					(size 0.7 0.7)
					(thickness 0.15)
				)
				(justify left bottom mirror)
			)
		)
		(pad "" smd custom
			(at -1.7 -1.7 90)
			(size 0.62 0.62)
			(layers "B.Paste")
			(thermal_bridge_angle 90)
			(options
				(clearance outline)
				(anchor circle)
			)
			(primitives
				(gr_arc
					(start 1.266786 0.24747)
					(mid 0.285453 -0.29439)
					(end -0.250195 -1.279127)
					(width 0.2)
				)
				(gr_arc
					(start 1.259603 0.339191)
					(mid 0.218448 -0.232561)
					(end -0.34334 -1.279127)
					(width 0.2)
				)
				(gr_arc
					(start 1.255279 0.431435)
					(mid 0.152481 -0.169693)
					(end -0.436309 -1.279127)
					(width 0.2)
				)
				(gr_arc
					(start 1.253811 0.524161)
					(mid 0.087542 -0.105784)
					(end -0.529126 -1.279127)
					(width 0.2)
				)
				(gr_arc
					(start 1.275473 0.621136)
					(mid 0.0309 -0.033527)
					(end -0.621807 -1.279127)
					(width 0.2)
				)
				(gr_arc
					(start 1.263664 0.711602)
					(mid -0.037759 0.026651)
					(end -0.71437 -1.279127)
					(width 0.2)
				)
				(gr_arc
					(start 1.253435 0.802342)
					(mid -0.105837 0.087395)
					(end -0.806826 -1.279127)
					(width 0.2)
				)
				(gr_arc
					(start 1.267475 0.897258)
					(mid -0.165236 0.156885)
					(end -0.899187 -1.279127)
					(width 0.2)
				)
				(gr_arc
					(start 1.270645 0.990112)
					(mid -0.228522 0.222449)
					(end -0.991463 -1.279127)
					(width 0.2)
				)
				(gr_arc
					(start 1.266278 1.081674)
					(mid -0.294507 0.285313)
					(end -1.083663 -1.279127)
					(width 0.2)
				)
				(gr_line
					(start 1.279127 1.083663)
					(end 1.279127 0.250195)
					(width 0.2)
				)
				(gr_line
					(start -1.083663 -1.279127)
					(end -0.250195 -1.279127)
					(width 0.2)
				)
			)
		)
		(pad "" smd custom
			(at -1.7 1.7 180)
			(size 0.62 0.62)
			(layers "B.Paste")
			(thermal_bridge_angle 90)
			(options
				(clearance outline)
				(anchor circle)
			)
			(primitives
				(gr_arc
					(start 1.266786 0.24747)
					(mid 0.285453 -0.29439)
					(end -0.250195 -1.279127)
					(width 0.2)
				)
				(gr_arc
					(start 1.259603 0.339191)
					(mid 0.218448 -0.232561)
					(end -0.34334 -1.279127)
					(width 0.2)
				)
				(gr_arc
					(start 1.255279 0.431435)
					(mid 0.152481 -0.169693)
					(end -0.436309 -1.279127)
					(width 0.2)
				)
				(gr_arc
					(start 1.253811 0.524161)
					(mid 0.087542 -0.105784)
					(end -0.529126 -1.279127)
					(width 0.2)
				)
				(gr_arc
					(start 1.275473 0.621136)
					(mid 0.0309 -0.033527)
					(end -0.621807 -1.279127)
					(width 0.2)
				)
				(gr_arc
					(start 1.263664 0.711602)
					(mid -0.037759 0.026651)
					(end -0.71437 -1.279127)
					(width 0.2)
				)
				(gr_arc
					(start 1.253435 0.802342)
					(mid -0.105837 0.087395)
					(end -0.806826 -1.279127)
					(width 0.2)
				)
				(gr_arc
					(start 1.267475 0.897258)
					(mid -0.165236 0.156885)
					(end -0.899187 -1.279127)
					(width 0.2)
				)
				(gr_arc
					(start 1.270645 0.990112)
					(mid -0.228522 0.222449)
					(end -0.991463 -1.279127)
					(width 0.2)
				)
				(gr_arc
					(start 1.266278 1.081674)
					(mid -0.294507 0.285313)
					(end -1.083663 -1.279127)
					(width 0.2)
				)
				(gr_line
					(start 1.279127 1.083663)
					(end 1.279127 0.250195)
					(width 0.2)
				)
				(gr_line
					(start -1.083663 -1.279127)
					(end -0.250195 -1.279127)
					(width 0.2)
				)
			)
		)
		(pad "" smd custom
			(at 1.7 -1.7)
			(size 0.62 0.62)
			(layers "B.Paste")
			(thermal_bridge_angle 90)
			(options
				(clearance outline)
				(anchor circle)
			)
			(primitives
				(gr_arc
					(start 1.266786 0.24747)
					(mid 0.285453 -0.29439)
					(end -0.250195 -1.279127)
					(width 0.2)
				)
				(gr_arc
					(start 1.259603 0.339191)
					(mid 0.218448 -0.232561)
					(end -0.34334 -1.279127)
					(width 0.2)
				)
				(gr_arc
					(start 1.255279 0.431435)
					(mid 0.152481 -0.169693)
					(end -0.436309 -1.279127)
					(width 0.2)
				)
				(gr_arc
					(start 1.253811 0.524161)
					(mid 0.087542 -0.105784)
					(end -0.529126 -1.279127)
					(width 0.2)
				)
				(gr_arc
					(start 1.275473 0.621136)
					(mid 0.0309 -0.033527)
					(end -0.621807 -1.279127)
					(width 0.2)
				)
				(gr_arc
					(start 1.263664 0.711602)
					(mid -0.037759 0.026651)
					(end -0.71437 -1.279127)
					(width 0.2)
				)
				(gr_arc
					(start 1.253435 0.802342)
					(mid -0.105837 0.087395)
					(end -0.806826 -1.279127)
					(width 0.2)
				)
				(gr_arc
					(start 1.267475 0.897258)
					(mid -0.165236 0.156885)
					(end -0.899187 -1.279127)
					(width 0.2)
				)
				(gr_arc
					(start 1.270645 0.990112)
					(mid -0.228522 0.222449)
					(end -0.991463 -1.279127)
					(width 0.2)
				)
				(gr_arc
					(start 1.266278 1.081674)
					(mid -0.294507 0.285313)
					(end -1.083663 -1.279127)
					(width 0.2)
				)
				(gr_line
					(start 1.279127 1.083663)
					(end 1.279127 0.250195)
					(width 0.2)
				)
				(gr_line
					(start -1.083663 -1.279127)
					(end -0.250195 -1.279127)
					(width 0.2)
				)
			)
		)
		(pad "" smd custom
			(at 1.7 1.7 270)
			(size 0.62 0.62)
			(layers "B.Paste")
			(thermal_bridge_angle 90)
			(options
				(clearance outline)
				(anchor circle)
			)
			(primitives
				(gr_arc
					(start 1.266786 0.24747)
					(mid 0.285453 -0.29439)
					(end -0.250195 -1.279127)
					(width 0.2)
				)
				(gr_arc
					(start 1.259603 0.339191)
					(mid 0.218448 -0.232561)
					(end -0.34334 -1.279127)
					(width 0.2)
				)
				(gr_arc
					(start 1.255279 0.431435)
					(mid 0.152481 -0.169693)
					(end -0.436309 -1.279127)
					(width 0.2)
				)
				(gr_arc
					(start 1.253811 0.524161)
					(mid 0.087542 -0.105784)
					(end -0.529126 -1.279127)
					(width 0.2)
				)
				(gr_arc
					(start 1.275473 0.621136)
					(mid 0.0309 -0.033527)
					(end -0.621807 -1.279127)
					(width 0.2)
				)
				(gr_arc
					(start 1.263664 0.711602)
					(mid -0.037759 0.026651)
					(end -0.71437 -1.279127)
					(width 0.2)
				)
				(gr_arc
					(start 1.253435 0.802342)
					(mid -0.105837 0.087395)
					(end -0.806826 -1.279127)
					(width 0.2)
				)
				(gr_arc
					(start 1.267475 0.897258)
					(mid -0.165236 0.156885)
					(end -0.899187 -1.279127)
					(width 0.2)
				)
				(gr_arc
					(start 1.270645 0.990112)
					(mid -0.228522 0.222449)
					(end -0.991463 -1.279127)
					(width 0.2)
				)
				(gr_arc
					(start 1.266278 1.081674)
					(mid -0.294507 0.285313)
					(end -1.083663 -1.279127)
					(width 0.2)
				)
				(gr_line
					(start 1.279127 1.083663)
					(end 1.279127 0.250195)
					(width 0.2)
				)
				(gr_line
					(start -1.083663 -1.279127)
					(end -0.250195 -1.279127)
					(width 0.2)
				)
			)
		)
		(pad "1" thru_hole circle
			(at 0 0 180)
			(size 6 6)
			(drill 3.7)
			(layers "*.Cu" "*.Mask")
			(remove_unused_layers no)
			(net 1 "GND")
			(pintype "passive")
		)
	)
	(footprint "antmicro-footprints:TP_SMD_0.75mm"
		(layer "B.Cu")
		(at 103.275 102.55 -90)
		(property "Reference" "TP37"
			(at -1.04 -1.365 90)
			(layer "B.SilkS")
			(hide yes)
			(effects
				(font
					(size 0.7 0.7)
					(thickness 0.15)
				)
				(justify left bottom mirror)
			)
		)
		(property "Value" "TP_0.75mm_SMD"
			(at 0 -1.2 90)
			(layer "B.Fab")
			(effects
				(font
					(size 0.7 0.7)
					(thickness 0.15)
				)
				(justify left bottom mirror)
			)
		)
		(property "Footprint" "antmicro-footprints:TP_SMD_0.75mm"
			(at 0 0 -90)
			(layer "F.Fab")
			(hide yes)
			(effects
				(font
					(size 1.27 1.27)
					(thickness 0.15)
				)
			)
		)
		(property "Author" "Antmicro"
			(at 0.725 205.825 0)
			(layer "B.Fab")
			(hide yes)
			(effects
				(font
					(size 1 1)
					(thickness 0.15)
				)
				(justify mirror)
			)
		)
		(property "License" "Apache-2.0"
			(at 0.725 205.825 0)
			(layer "B.Fab")
			(hide yes)
			(effects
				(font
					(size 1 1)
					(thickness 0.15)
				)
				(justify mirror)
			)
		)
		(property "MPN" ""
			(at 0.725 205.825 0)
			(layer "B.Fab")
			(hide yes)
			(effects
				(font
					(size 1 1)
					(thickness 0.15)
				)
				(justify mirror)
			)
		)
		(property "Manufacturer" ""
			(at 0.725 205.825 0)
			(layer "B.Fab")
			(hide yes)
			(effects
				(font
					(size 1 1)
					(thickness 0.15)
				)
				(justify mirror)
			)
		)
		(sheetname "CSI")
		(sheetfile "csi.kicad_sch")
		(attr exclude_from_pos_files exclude_from_bom)
		(fp_circle
			(center 0 0)
			(end 0.475 0)
			(stroke
				(width 0.05)
				(type default)
			)
			(fill none)
			(layer "B.CrtYd")
		)
		(fp_text user "License: Apache-2.0"
			(at -0.4 -5.101 90)
			(layer "B.Fab")
			(hide yes)
			(effects
				(font
					(size 0.7 0.7)
					(thickness 0.15)
				)
				(justify left bottom mirror)
			)
		)
		(fp_text user "Author: Antmicro"
			(at -0.4 -3.901 90)
			(layer "B.Fab")
			(hide yes)
			(effects
				(font
					(size 0.7 0.7)
					(thickness 0.15)
				)
				(justify left bottom mirror)
			)
		)
		(fp_text user "${REFERENCE}"
			(at -0.4 -2.7 90)
			(layer "B.Fab")
			(hide yes)
			(effects
				(font
					(size 0.7 0.7)
					(thickness 0.15)
				)
				(justify left bottom mirror)
			)
		)
		(pad "1" smd circle
			(at 0 0 270)
			(size 0.75 0.75)
			(layers "B.Cu" "B.Mask")
			(net 536 "/CSI/MUX_I2C_4_SCL")
			(pinfunction "1")
			(pintype "passive")
		)
	)
	(footprint "antmicro-footprints:R_0402_1005Metric"
		(layer "B.Cu")
		(at 46.54 73.475 180)
		(descr "Resistor SMD 0402")
		(tags "resistor SMD 0402")
		(property "Reference" "R251"
			(at -1.36 -2.225 180)
			(layer "B.SilkS")
			(effects
				(font
					(size 0.7 0.7)
					(thickness 0.15)
				)
				(justify left bottom mirror)
			)
		)
		(property "Value" "R_10k_0402"
			(at 0 -1.4 0)
			(layer "B.Fab")
			(effects
				(font
					(size 0.7 0.7)
					(thickness 0.15)
				)
				(justify left bottom mirror)
			)
		)
		(property "Footprint" "antmicro-footprints:R_0402_1005Metric"
			(at 0 0 180)
			(layer "F.Fab")
			(hide yes)
			(effects
				(font
					(size 1.27 1.27)
					(thickness 0.15)
				)
			)
		)
		(property "Datasheet" "https://www.bourns.com/docs/product-datasheets/cr.pdf"
			(at 0 0 180)
			(layer "F.Fab")
			(hide yes)
			(effects
				(font
					(size 1.27 1.27)
					(thickness 0.15)
				)
			)
		)
		(property "Author" "Antmicro"
			(at 93.8 146.8 0)
			(layer "B.Fab")
			(hide yes)
			(effects
				(font
					(size 1 1)
					(thickness 0.15)
				)
				(justify mirror)
			)
		)
		(property "License" "Apache-2.0"
			(at 93.8 146.8 0)
			(layer "B.Fab")
			(hide yes)
			(effects
				(font
					(size 1 1)
					(thickness 0.15)
				)
				(justify mirror)
			)
		)
		(property "MPN" "CR0402-FX-1002GLF"
			(at 93.8 146.8 0)
			(layer "B.Fab")
			(hide yes)
			(effects
				(font
					(size 1 1)
					(thickness 0.15)
				)
				(justify mirror)
			)
		)
		(property "Manufacturer" "Bourns"
			(at 93.8 146.8 0)
			(layer "B.Fab")
			(hide yes)
			(effects
				(font
					(size 1 1)
					(thickness 0.15)
				)
				(justify mirror)
			)
		)
		(property "Tolerance" "1%"
			(at 93.8 146.8 0)
			(layer "B.Fab")
			(hide yes)
			(effects
				(font
					(size 1 1)
					(thickness 0.15)
				)
				(justify mirror)
			)
		)
		(property "Val" "10k"
			(at 93.8 146.8 0)
			(layer "B.Fab")
			(hide yes)
			(effects
				(font
					(size 1 1)
					(thickness 0.15)
				)
				(justify mirror)
			)
		)
		(sheetname "Supply")
		(sheetfile "supply.kicad_sch")
		(attr smd)
		(fp_rect
			(start -0.925 0.47)
			(end 0.925 -0.47)
			(stroke
				(width 0.05)
				(type default)
			)
			(fill none)
			(layer "B.CrtYd")
		)
		(fp_rect
			(start -0.5 0.25)
			(end 0.5 -0.25)
			(stroke
				(width 0.15)
				(type solid)
			)
			(fill none)
			(layer "B.Fab")
		)
		(fp_text user "${REFERENCE}"
			(at -0.95 -3.168 0)
			(layer "B.Fab")
			(hide yes)
			(effects
				(font
					(size 0.7 0.7)
					(thickness 0.15)
				)
				(justify left bottom mirror)
			)
		)
		(fp_text user "Author: Antmicro"
			(at -0.95 -4.169 0)
			(layer "B.Fab")
			(hide yes)
			(effects
				(font
					(size 0.7 0.7)
					(thickness 0.15)
				)
				(justify left bottom mirror)
			)
		)
		(fp_text user "License: Apache-2.0"
			(at -0.95 -5.169 0)
			(layer "B.Fab")
			(hide yes)
			(effects
				(font
					(size 0.7 0.7)
					(thickness 0.15)
				)
				(justify left bottom mirror)
			)
		)
		(pad "1" smd roundrect
			(at -0.48 0 180)
			(size 0.59 0.64)
			(layers "B.Cu" "B.Paste" "B.Mask")
			(roundrect_rratio 0.25)
			(net 1 "GND")
			(pintype "passive")
		)
		(pad "2" smd roundrect
			(at 0.48 0 180)
			(size 0.59 0.64)
			(layers "B.Cu" "B.Paste" "B.Mask")
			(roundrect_rratio 0.25)
			(net 718 "Net-(Q14-Pad2)")
			(pintype "passive")
		)
	)
	(footprint "antmicro-footprints:C_0402_1005Metric"
		(layer "B.Cu")
		(at 136.7 117.55)
		(descr "Capacitor SMD 0402")
		(tags "capacitor SMD 0402")
		(property "Reference" "C42"
			(at 1.1 1.3 180)
			(layer "B.SilkS")
			(effects
				(font
					(size 0.7 0.7)
					(thickness 0.15)
				)
				(justify left bottom mirror)
			)
		)
		(property "Value" "C_100n_0402"
			(at 0 -1.4 180)
			(layer "B.Fab")
			(effects
				(font
					(size 0.7 0.7)
					(thickness 0.15)
				)
				(justify left bottom mirror)
			)
		)
		(property "Footprint" "antmicro-footprints:C_0402_1005Metric"
			(at 0 0 0)
			(layer "F.Fab")
			(hide yes)
			(effects
				(font
					(size 1.27 1.27)
					(thickness 0.15)
				)
			)
		)
		(property "Datasheet" "https://www.murata.com/products/productdetail?partno=GRM155R61H104KE14%23"
			(at 0 0 0)
			(layer "F.Fab")
			(hide yes)
			(effects
				(font
					(size 1.27 1.27)
					(thickness 0.15)
				)
			)
		)
		(property "Author" "Antmicro"
			(at 0 0 0)
			(layer "B.Fab")
			(hide yes)
			(effects
				(font
					(size 1 1)
					(thickness 0.15)
				)
				(justify mirror)
			)
		)
		(property "Dielectric" "X5R"
			(at 0 0 0)
			(layer "B.Fab")
			(hide yes)
			(effects
				(font
					(size 1 1)
					(thickness 0.15)
				)
				(justify mirror)
			)
		)
		(property "License" "Apache-2.0"
			(at 0 0 0)
			(layer "B.Fab")
			(hide yes)
			(effects
				(font
					(size 1 1)
					(thickness 0.15)
				)
				(justify mirror)
			)
		)
		(property "MPN" "GRM155R61H104KE14D"
			(at 0 0 0)
			(layer "B.Fab")
			(hide yes)
			(effects
				(font
					(size 1 1)
					(thickness 0.15)
				)
				(justify mirror)
			)
		)
		(property "Manufacturer" "Murata"
			(at 0 0 0)
			(layer "B.Fab")
			(hide yes)
			(effects
				(font
					(size 1 1)
					(thickness 0.15)
				)
				(justify mirror)
			)
		)
		(property "Val" "100n"
			(at 0 0 0)
			(layer "B.Fab")
			(hide yes)
			(effects
				(font
					(size 1 1)
					(thickness 0.15)
				)
				(justify mirror)
			)
		)
		(property "Voltage" "50V"
			(at 0 0 0)
			(layer "B.Fab")
			(hide yes)
			(effects
				(font
					(size 1 1)
					(thickness 0.15)
				)
				(justify mirror)
			)
		)
		(sheetname "CSI")
		(sheetfile "csi.kicad_sch")
		(attr smd)
		(fp_rect
			(start -0.925 0.47)
			(end 0.925 -0.47)
			(stroke
				(width 0.05)
				(type default)
			)
			(fill none)
			(layer "B.CrtYd")
		)
		(fp_line
			(start -0.494 -0.248)
			(end 0.504 -0.248)
			(stroke
				(width 0.15)
				(type solid)
			)
			(layer "B.Fab")
		)
		(fp_line
			(start -0.494 0.25)
			(end -0.494 -0.248)
			(stroke
				(width 0.15)
				(type solid)
			)
			(layer "B.Fab")
		)
		(fp_line
			(start 0.504 -0.248)
			(end 0.504 0.25)
			(stroke
				(width 0.15)
				(type solid)
			)
			(layer "B.Fab")
		)
		(fp_line
			(start 0.504 0.25)
			(end -0.494 0.25)
			(stroke
				(width 0.15)
				(type solid)
			)
			(layer "B.Fab")
		)
		(fp_text user "${REFERENCE}"
			(at -0.932 -3.168 180)
			(layer "B.Fab")
			(hide yes)
			(effects
				(font
					(size 0.7 0.7)
					(thickness 0.15)
				)
				(justify left bottom mirror)
			)
		)
		(fp_text user "License: Apache-2.0"
			(at -0.932 -5.17 180)
			(layer "B.Fab")
			(hide yes)
			(effects
				(font
					(size 0.7 0.7)
					(thickness 0.15)
				)
				(justify left bottom mirror)
			)
		)
		(fp_text user "Author: Antmicro"
			(at -0.932 -4.17 180)
			(layer "B.Fab")
			(hide yes)
			(effects
				(font
					(size 0.7 0.7)
					(thickness 0.15)
				)
				(justify left bottom mirror)
			)
		)
		(pad "1" smd roundrect
			(at -0.48 0)
			(size 0.59 0.64)
			(layers "B.Cu" "B.Paste" "B.Mask")
			(roundrect_rratio 0.25)
			(net 99 "+5V")
			(pintype "passive")
		)
		(pad "2" smd roundrect
			(at 0.48 0)
			(size 0.59 0.64)
			(layers "B.Cu" "B.Paste" "B.Mask")
			(roundrect_rratio 0.25)
			(net 1 "GND")
			(pintype "passive")
		)
	)
)
